# T6G (Grand Teton) — schematic netlist excerpt (pin names and nets, part order shuffled) for the footprints in the layout excerpt that follows; sources: Cadence DE-HDL packaged netlist, KiCad conversion of 04192023_DAF0TMB3IC0_F0TG_MB_C_brd_V02_OCP.brd

R3503  Q_RES  4.7K 5% CHIP  pkg 0402LF  page 126 : A = P3V3_AUX ; B = GPU_FPGA_EROT_FATALERR
PC6819  Q_CAP  22UF 16V 20% X6S  pkg C0805  page 365 : A = SW_P12V_AUX_P0V9_RETIMER_CPU1_FLT ; B = GND
C352  Q_CAP  0.1UF 16V 10% X7R  pkg C0402  page 83 : A = P1V8_AUX ; B = GND

(kicad_pcb
	(version 20260206)
	(generator "pcbnew")
	(generator_version "10.0")
	(general
		(thickness 1.6)
		(legacy_teardrops no)
	)
	(paper "A4")
	(title_block
		(title "04192023_DAF0TMB3IC0_F0TG_MB_C_brd_V02_OCP.brd")
		(comment 1 "Grand Teton / footprints 7300-7302 of 8354")
	)
	(layers
		(0 "F.Cu" signal "TOP")
		(4 "In1.Cu" signal "GND")
		(6 "In2.Cu" signal "IN1")
		(8 "In3.Cu" signal "GND1")
		(10 "In4.Cu" signal "IN2")
		(12 "In5.Cu" signal "GND2")
		(14 "In6.Cu" signal "IN3")
		(16 "In7.Cu" signal "GND3")
		(18 "In8.Cu" signal "VCC")
		(20 "In9.Cu" signal "VCC1")
		(22 "In10.Cu" signal "GND4")
		(24 "In11.Cu" signal "IN4")
		(26 "In12.Cu" signal "GND5")
		(28 "In13.Cu" signal "IN5")
		(30 "In14.Cu" signal "GND6")
		(32 "In15.Cu" signal "IN6")
		(34 "In16.Cu" signal "GND7")
		(2 "B.Cu" signal "BOTTOM")
		(9 "F.Adhes" user "F.Adhesive")
		(11 "B.Adhes" user "B.Adhesive")
		(13 "F.Paste" user "Package Geometry/Pastemask Top")
		(15 "B.Paste" user "Package Geometry/Pastemask Bottom")
		(5 "F.SilkS" user "Ref Des/Silkscreen Top")
		(7 "B.SilkS" user "Ref Des/Silkscreen Bottom")
		(1 "F.Mask" user "Board Geometry/Soldermask Top")
		(3 "B.Mask" user "Board Geometry/Soldermask Bottom")
		(17 "Dwgs.User" user "User.Drawings")
		(19 "Cmts.User" user "User.Comments")
		(21 "Eco1.User" user "User.Eco1")
		(23 "Eco2.User" user "User.Eco2")
		(25 "Edge.Cuts" user "Board Geometry/Outline")
		(27 "Margin" user)
		(31 "F.CrtYd" user "Package Geometry/Place Bound Top")
		(29 "B.CrtYd" user "Package Geometry/Place Bound Bottom")
		(35 "F.Fab" user "Ref Des/Assembly Top")
		(33 "B.Fab" user "Ref Des/Assembly Bottom")
	)
	(footprint ""
		(layer "B.Cu")
		(at 180.0352 -106.71048 90)
		(property "Reference" "C352"
			(at 0 0 90)
			(layer "B.SilkS")
			(hide yes)
			(effects
				(font
					(size 1.27 1.27)
				)
				(justify mirror)
			)
		)
		(property "Value" ""
			(at 0 0 90)
			(layer "B.Fab")
			(effects
				(font
					(size 1.27 1.27)
				)
				(justify mirror)
			)
		)
		(duplicate_pad_numbers_are_jumpers no)
		(fp_line
			(start 0.7874 -0.4064)
			(end -0.7874 -0.4064)
			(stroke
				(width 0.1524)
				(type default)
			)
			(layer "B.SilkS")
		)
		(fp_line
			(start -0.7874 -0.4064)
			(end -0.7874 0.4064)
			(stroke
				(width 0.1524)
				(type default)
			)
			(layer "B.SilkS")
		)
		(fp_line
			(start 0.7874 0.4064)
			(end 0.7874 -0.4064)
			(stroke
				(width 0.1524)
				(type default)
			)
			(layer "B.SilkS")
		)
		(fp_line
			(start -0.7874 0.4064)
			(end 0.7874 0.4064)
			(stroke
				(width 0.1524)
				(type default)
			)
			(layer "B.SilkS")
		)
		(fp_line
			(start 0.67945 -0.305054)
			(end 0.12065 -0.305054)
			(stroke
				(width 0.1)
				(type default)
			)
			(layer "B.Fab")
		)
		(fp_line
			(start 0.12065 -0.305054)
			(end 0.12065 -0.2794)
			(stroke
				(width 0.1)
				(type default)
			)
			(layer "B.Fab")
		)
		(fp_line
			(start -0.12065 -0.3048)
			(end -0.67945 -0.3048)
			(stroke
				(width 0.1)
				(type default)
			)
			(layer "B.Fab")
		)
		(fp_line
			(start -0.67945 -0.3048)
			(end -0.67945 0.3048)
			(stroke
				(width 0.1)
				(type default)
			)
			(layer "B.Fab")
		)
		(fp_line
			(start 0.12065 -0.2794)
			(end -0.12065 -0.2794)
			(stroke
				(width 0.1)
				(type default)
			)
			(layer "B.Fab")
		)
		(fp_line
			(start -0.12065 -0.2794)
			(end -0.12065 -0.3048)
			(stroke
				(width 0.1)
				(type default)
			)
			(layer "B.Fab")
		)
		(fp_line
			(start 0.12065 0.2794)
			(end 0.12065 0.3048)
			(stroke
				(width 0.1)
				(type default)
			)
			(layer "B.Fab")
		)
		(fp_line
			(start -0.120396 0.2794)
			(end 0.12065 0.2794)
			(stroke
				(width 0.1)
				(type default)
			)
			(layer "B.Fab")
		)
		(fp_line
			(start 0.67945 0.3048)
			(end 0.67945 -0.305054)
			(stroke
				(width 0.1)
				(type default)
			)
			(layer "B.Fab")
		)
		(fp_line
			(start 0.12065 0.3048)
			(end 0.67945 0.3048)
			(stroke
				(width 0.1)
				(type default)
			)
			(layer "B.Fab")
		)
		(fp_line
			(start -0.120396 0.3048)
			(end -0.120396 0.2794)
			(stroke
				(width 0.1)
				(type default)
			)
			(layer "B.Fab")
		)
		(fp_line
			(start -0.67945 0.3048)
			(end -0.120396 0.3048)
			(stroke
				(width 0.1)
				(type default)
			)
			(layer "B.Fab")
		)
		(pad "1" smd circle
			(at 0.40005 0 270)
			(size 0 0)
			(layers "B.Cu" "B.Mask" "B.Paste")
			(net "P1V8_AUX")
		)
		(pad "2" smd circle
			(at -0.40005 0 270)
			(size 0 0)
			(layers "B.Cu" "B.Mask" "B.Paste")
			(net "GND")
		)
	)
	(footprint ""
		(layer "B.Cu")
		(at 18.01749 -400.953732)
		(property "Reference" "PC6819"
			(at 0 0 0)
			(layer "B.SilkS")
			(hide yes)
			(effects
				(font
					(size 1.27 1.27)
				)
				(justify mirror)
			)
		)
		(property "Value" ""
			(at 0 0 0)
			(layer "B.Fab")
			(effects
				(font
					(size 1.27 1.27)
				)
				(justify mirror)
			)
		)
		(duplicate_pad_numbers_are_jumpers no)
		(fp_line
			(start -1.524 -0.762)
			(end -1.524 0.762)
			(stroke
				(width 0.1524)
				(type default)
			)
			(layer "B.SilkS")
		)
		(fp_line
			(start -1.524 0.762)
			(end 1.524 0.762)
			(stroke
				(width 0.1524)
				(type default)
			)
			(layer "B.SilkS")
		)
		(fp_line
			(start 1.524 -0.762)
			(end -1.524 -0.762)
			(stroke
				(width 0.1524)
				(type default)
			)
			(layer "B.SilkS")
		)
		(fp_line
			(start 1.524 0.762)
			(end 1.524 -0.762)
			(stroke
				(width 0.1524)
				(type default)
			)
			(layer "B.SilkS")
		)
		(fp_line
			(start -1.1049 -0.724916)
			(end 1.1049 -0.724916)
			(stroke
				(width 0.1)
				(type default)
			)
			(layer "B.Fab")
		)
		(fp_line
			(start -1.1049 0.724916)
			(end -1.1049 -0.724916)
			(stroke
				(width 0.1)
				(type default)
			)
			(layer "B.Fab")
		)
		(fp_line
			(start 1.1049 -0.724916)
			(end 1.1049 0.724916)
			(stroke
				(width 0.1)
				(type default)
			)
			(layer "B.Fab")
		)
		(fp_line
			(start 1.1049 0.724916)
			(end -1.1049 0.724916)
			(stroke
				(width 0.1)
				(type default)
			)
			(layer "B.Fab")
		)
		(pad "1" smd rect
			(at 0.889 0)
			(size 1.016 1.27)
			(layers "B.Cu" "B.Mask" "B.Paste")
			(net "SW_P12V_AUX_P0V9_RETIMER_CPU1_FLT")
		)
		(pad "2" smd rect
			(at -0.889 0)
			(size 1.016 1.27)
			(layers "B.Cu" "B.Mask" "B.Paste")
			(net "GND")
		)
	)
	(footprint ""
		(layer "B.Cu")
		(at 111.379 -418.211 180)
		(property "Reference" "R3503"
			(at 0 0 0)
			(layer "B.SilkS")
			(hide yes)
			(effects
				(font
					(size 1.27 1.27)
				)
				(justify mirror)
			)
		)
		(property "Value" ""
			(at 0 0 0)
			(layer "B.Fab")
			(effects
				(font
					(size 1.27 1.27)
				)
				(justify mirror)
			)
		)
		(duplicate_pad_numbers_are_jumpers no)
		(fp_line
			(start 0.7874 0.4064)
			(end 0.7874 -0.4064)
			(stroke
				(width 0.1524)
				(type default)
			)
			(layer "B.SilkS")
		)
		(fp_line
			(start 0.7874 -0.4064)
			(end -0.7874 -0.4064)
			(stroke
				(width 0.1524)
				(type default)
			)
			(layer "B.SilkS")
		)
		(fp_line
			(start -0.7874 0.4064)
			(end 0.7874 0.4064)
			(stroke
				(width 0.1524)
				(type default)
			)
			(layer "B.SilkS")
		)
		(fp_line
			(start -0.7874 -0.4064)
			(end -0.7874 0.4064)
			(stroke
				(width 0.1524)
				(type default)
			)
			(layer "B.SilkS")
		)
		(fp_line
			(start 0.67945 0.3048)
			(end 0.67945 -0.305054)
			(stroke
				(width 0.1)
				(type default)
			)
			(layer "B.Fab")
		)
		(fp_line
			(start 0.67945 -0.305054)
			(end 0.12065 -0.305054)
			(stroke
				(width 0.1)
				(type default)
			)
			(layer "B.Fab")
		)
		(fp_line
			(start 0.12065 0.3048)
			(end 0.67945 0.3048)
			(stroke
				(width 0.1)
				(type default)
			)
			(layer "B.Fab")
		)
		(fp_line
			(start 0.12065 0.2794)
			(end 0.12065 0.3048)
			(stroke
				(width 0.1)
				(type default)
			)
			(layer "B.Fab")
		)
		(fp_line
			(start 0.12065 -0.2794)
			(end -0.12065 -0.2794)
			(stroke
				(width 0.1)
				(type default)
			)
			(layer "B.Fab")
		)
		(fp_line
			(start 0.12065 -0.305054)
			(end 0.12065 -0.2794)
			(stroke
				(width 0.1)
				(type default)
			)
			(layer "B.Fab")
		)
		(fp_line
			(start -0.120396 0.3048)
			(end -0.120396 0.2794)
			(stroke
				(width 0.1)
				(type default)
			)
			(layer "B.Fab")
		)
		(fp_line
			(start -0.120396 0.2794)
			(end 0.12065 0.2794)
			(stroke
				(width 0.1)
				(type default)
			)
			(layer "B.Fab")
		)
		(fp_line
			(start -0.12065 -0.2794)
			(end -0.12065 -0.3048)
			(stroke
				(width 0.1)
				(type default)
			)
			(layer "B.Fab")
		)
		(fp_line
			(start -0.12065 -0.3048)
			(end -0.67945 -0.3048)
			(stroke
				(width 0.1)
				(type default)
			)
			(layer "B.Fab")
		)
		(fp_line
			(start -0.67945 0.3048)
			(end -0.120396 0.3048)
			(stroke
				(width 0.1)
				(type default)
			)
			(layer "B.Fab")
		)
		(fp_line
			(start -0.67945 -0.3048)
			(end -0.67945 0.3048)
			(stroke
				(width 0.1)
				(type default)
			)
			(layer "B.Fab")
		)
		(pad "1" smd circle
			(at 0.40005 0)
			(size 0 0)
			(layers "B.Cu" "B.Mask" "B.Paste")
			(net "P3V3_AUX")
		)
		(pad "2" smd circle
			(at -0.40005 0)
			(size 0 0)
			(layers "B.Cu" "B.Mask" "B.Paste")
			(net "GPU_FPGA_EROT_FATALERR")
		)
	)
)
